# BASEBOARD_FAB2 (Tioga Pass) — schematic netlist excerpt (pin names and nets, part order shuffled) for the footprints in the layout excerpt that follows; sources: Cadence DE-HDL packaged netlist, KiCad conversion of Wiwynn_Tioga_Pass_MB.brd

C7E5  CAP_A  0.1UF 16V 10% X7R  pkg 0402V  page 198 : A = P12V_STBY ; B = GND
C4F5  CAPP  68UF 16V 20% TANT  pkg 3018  page 195 : A = P12V_STBY ; B = GND
R8A4  RES  100.0K 1% CHIP  pkg 0402  page 235 : A = VR_FET_SW_P12V_STBY_PVDDQ_DEF ; B = VR_PVNN_PCH_VINSEN

(kicad_pcb
	(version 20260206)
	(generator "pcbnew")
	(generator_version "10.0")
	(general
		(thickness 1.6)
		(legacy_teardrops no)
	)
	(paper "A4")
	(title_block
		(title "Wiwynn_Tioga_Pass_MB.brd")
		(comment 1 "Tioga Pass / footprints 1946-1948 of 4770")
	)
	(layers
		(0 "F.Cu" signal "TOP")
		(4 "In1.Cu" signal "L2GND")
		(6 "In2.Cu" signal "L3")
		(8 "In3.Cu" signal "L4GND")
		(10 "In4.Cu" signal "L5")
		(12 "In5.Cu" signal "L6GND")
		(14 "In6.Cu" signal "L7VCC")
		(16 "In7.Cu" signal "L8VCC")
		(18 "In8.Cu" signal "L9GND")
		(20 "In9.Cu" signal "L10")
		(22 "In10.Cu" signal "L11GND")
		(24 "In11.Cu" signal "L12")
		(26 "In12.Cu" signal "L13GND")
		(2 "B.Cu" signal "BOTTOM")
		(9 "F.Adhes" user "F.Adhesive")
		(11 "B.Adhes" user "B.Adhesive")
		(13 "F.Paste" user "Package Geometry/Pastemask Top")
		(15 "B.Paste" user "Package Geometry/Pastemask Bottom")
		(5 "F.SilkS" user "Ref Des/Silkscreen Top")
		(7 "B.SilkS" user "Ref Des/Silkscreen Bottom")
		(1 "F.Mask" user "Board Geometry/Soldermask Top")
		(3 "B.Mask" user "Board Geometry/Soldermask Bottom")
		(17 "Dwgs.User" user "User.Drawings")
		(19 "Cmts.User" user "User.Comments")
		(21 "Eco1.User" user "User.Eco1")
		(23 "Eco2.User" user "User.Eco2")
		(25 "Edge.Cuts" user "Board Geometry/Outline")
		(27 "Margin" user)
		(31 "F.CrtYd" user "Package Geometry/Place Bound Top")
		(29 "B.CrtYd" user "Package Geometry/Place Bound Bottom")
		(35 "F.Fab" user "Ref Des/Assembly Top")
		(33 "B.Fab" user "Ref Des/Assembly Bottom")
	)
	(footprint ""
		(layer "F.Cu")
		(at 177.927 -32.766 -90)
		(property "Reference" "C4F5"
			(at 3.32867 1.524 0)
			(unlocked yes)
			(layer "F.SilkS")
			(effects
				(font
					(size 0.7874 0.5842)
					(thickness 0.1524)
				)
			)
		)
		(property "Value" ""
			(at 0 0 270)
			(layer "F.Fab")
			(effects
				(font
					(size 1.27 1.27)
				)
			)
		)
		(duplicate_pad_numbers_are_jumpers no)
		(fp_line
			(start -2.286 7.366)
			(end -1.60147 7.366)
			(stroke
				(width 0.1524)
				(type default)
			)
			(layer "F.SilkS")
		)
		(fp_line
			(start -2.286 7.366)
			(end -2.286 1.632712)
			(stroke
				(width 0.1524)
				(type default)
			)
			(layer "F.SilkS")
		)
		(fp_line
			(start 2.286 7.366)
			(end 1.600708 7.366)
			(stroke
				(width 0.1524)
				(type default)
			)
			(layer "F.SilkS")
		)
		(fp_line
			(start 2.286 7.366)
			(end 2.286 1.63195)
			(stroke
				(width 0.1524)
				(type default)
			)
			(layer "F.SilkS")
		)
		(fp_line
			(start -2.563114 1.633982)
			(end -1.6002 1.633728)
			(stroke
				(width 0.1524)
				(type default)
			)
			(layer "F.SilkS")
		)
		(fp_line
			(start 2.504948 1.633982)
			(end 1.6002 1.633728)
			(stroke
				(width 0.1524)
				(type default)
			)
			(layer "F.SilkS")
		)
		(fp_line
			(start -2.56286 -1.616456)
			(end -2.563114 1.633982)
			(stroke
				(width 0.1524)
				(type default)
			)
			(layer "F.SilkS")
		)
		(fp_line
			(start -1.6002 -1.616456)
			(end -2.56286 -1.616456)
			(stroke
				(width 0.1524)
				(type default)
			)
			(layer "F.SilkS")
		)
		(fp_line
			(start 1.6002 -1.616456)
			(end 2.504948 -1.61671)
			(stroke
				(width 0.1524)
				(type default)
			)
			(layer "F.SilkS")
		)
		(fp_line
			(start 2.504948 -1.61671)
			(end 2.504948 1.633982)
			(stroke
				(width 0.1524)
				(type default)
			)
			(layer "F.SilkS")
		)
		(fp_rect
			(start -2.286 7.366)
			(end 2.286 -0.254)
			(stroke
				(width 0)
				(type default)
			)
			(fill no)
			(layer "F.CrtYd")
		)
		(fp_line
			(start -2.286 7.366)
			(end -2.286 -0.254)
			(stroke
				(width 0.1)
				(type default)
			)
			(layer "F.Fab")
		)
		(fp_line
			(start 2.286 7.366)
			(end -2.286 7.366)
			(stroke
				(width 0.1)
				(type default)
			)
			(layer "F.Fab")
		)
		(fp_line
			(start -2.286 -0.254)
			(end 2.286 -0.254)
			(stroke
				(width 0.1)
				(type default)
			)
			(layer "F.Fab")
		)
		(fp_line
			(start 2.286 -0.254)
			(end 2.286 7.366)
			(stroke
				(width 0.1)
				(type default)
			)
			(layer "F.Fab")
		)
		(pad "1" smd rect
			(at 0 0 270)
			(size 2.54 3.048)
			(layers "F.Cu" "F.Mask" "F.Paste")
			(net "P12V_STBY")
		)
		(pad "2" smd rect
			(at 0 7.112 270)
			(size 2.54 3.048)
			(layers "F.Cu" "F.Mask" "F.Paste")
			(net "GND")
		)
	)
	(footprint ""
		(layer "F.Cu")
		(at 390.578594 -153.47569 90)
		(property "Reference" "R8A4"
			(at 0 0 90)
			(layer "F.SilkS")
			(hide yes)
			(effects
				(font
					(size 1.27 1.27)
				)
			)
		)
		(property "Value" ""
			(at 0 0 90)
			(layer "F.Fab")
			(effects
				(font
					(size 1.27 1.27)
				)
			)
		)
		(duplicate_pad_numbers_are_jumpers no)
		(fp_poly
			(pts
				(xy -0.2794 -0.1016) (xy 0.2794 -0.1016) (xy 0.2794 0.9906) (xy -0.2794 0.9906)
			)
			(stroke
				(width 0)
				(type default)
			)
			(fill no)
			(layer "F.CrtYd")
		)
		(fp_line
			(start 0.2794 -0.1016)
			(end -0.2794 -0.1016)
			(stroke
				(width 0.1)
				(type default)
			)
			(layer "F.Fab")
		)
		(fp_line
			(start -0.2794 -0.1016)
			(end -0.2794 0.9906)
			(stroke
				(width 0.1)
				(type default)
			)
			(layer "F.Fab")
		)
		(fp_line
			(start 0.2794 0.9906)
			(end 0.2794 -0.1016)
			(stroke
				(width 0.1)
				(type default)
			)
			(layer "F.Fab")
		)
		(fp_line
			(start -0.2794 0.9906)
			(end 0.2794 0.9906)
			(stroke
				(width 0.1)
				(type default)
			)
			(layer "F.Fab")
		)
		(pad "1" smd rect
			(at 0 0 90)
			(size 0.508 0.508)
			(layers "F.Cu" "F.Mask" "F.Paste")
			(net "VR_FET_SW_P12V_STBY_PVDDQ_DEF")
		)
		(pad "2" smd rect
			(at 0 0.889 90)
			(size 0.508 0.508)
			(layers "F.Cu" "F.Mask" "F.Paste")
			(net "VR_PVNN_PCH_VINSEN")
		)
		(zone
			(layer "F.Cu")
			(hatch none 0.5)
			(connect_pads
				(clearance 0)
			)
			(min_thickness 0.25)
			(keepout
				(tracks allowed)
				(vias not_allowed)
				(pads allowed)
				(copperpour not_allowed)
				(footprints allowed)
			)
			(placement
				(enabled no)
				(sheetname "")
			)
			(fill
				(thermal_gap 0.5)
				(thermal_bridge_width 0.5)
				(island_removal_mode 0)
			)
			(polygon
				(pts
					(xy 390.832594 -153.22169) (xy 390.832594 -153.72969) (xy 391.213594 -153.72969) (xy 391.213594 -153.22169)
				)
			)
		)
		(zone
			(layer "F.Cu")
			(hatch none 0.5)
			(connect_pads
				(clearance 0)
			)
			(min_thickness 0.25)
			(keepout
				(tracks not_allowed)
				(vias allowed)
				(pads allowed)
				(copperpour not_allowed)
				(footprints allowed)
			)
			(placement
				(enabled no)
				(sheetname "")
			)
			(fill
				(thermal_gap 0.5)
				(thermal_bridge_width 0.5)
				(island_removal_mode 0)
			)
			(polygon
				(pts
					(xy 391.213594 -153.22169) (xy 391.213594 -153.72969) (xy 390.832594 -153.72969) (xy 390.832594 -153.22169)
				)
			)
		)
	)
	(footprint ""
		(layer "F.Cu")
		(at 497.781834 -23.657052 90)
		(property "Reference" "C7E5"
			(at 0 0 90)
			(layer "F.SilkS")
			(hide yes)
			(effects
				(font
					(size 1.27 1.27)
				)
			)
		)
		(property "Value" ""
			(at 0 0 90)
			(layer "F.Fab")
			(effects
				(font
					(size 1.27 1.27)
				)
			)
		)
		(duplicate_pad_numbers_are_jumpers no)
		(fp_rect
			(start 0.3048 0.9906)
			(end -0.3048 -0.1016)
			(stroke
				(width 0)
				(type default)
			)
			(fill no)
			(layer "F.CrtYd")
		)
		(fp_line
			(start 0.3048 -0.1016)
			(end -0.3048 -0.1016)
			(stroke
				(width 0.1)
				(type default)
			)
			(layer "F.Fab")
		)
		(fp_line
			(start -0.3048 -0.1016)
			(end -0.3048 0.9906)
			(stroke
				(width 0.1)
				(type default)
			)
			(layer "F.Fab")
		)
		(fp_line
			(start 0.3048 0.9906)
			(end 0.3048 -0.1016)
			(stroke
				(width 0.1)
				(type default)
			)
			(layer "F.Fab")
		)
		(fp_line
			(start -0.3048 0.9906)
			(end 0.3048 0.9906)
			(stroke
				(width 0.1)
				(type default)
			)
			(layer "F.Fab")
		)
		(pad "1" smd rect
			(at 0 0 90)
			(size 0.508 0.508)
			(layers "F.Cu" "F.Mask" "F.Paste")
			(net "P12V_STBY")
		)
		(pad "2" smd rect
			(at 0 0.889 90)
			(size 0.508 0.508)
			(layers "F.Cu" "F.Mask" "F.Paste")
			(net "GND")
		)
		(zone
			(layer "F.Cu")
			(hatch none 0.5)
			(connect_pads
				(clearance 0)
			)
			(min_thickness 0.25)
			(keepout
				(tracks allowed)
				(vias not_allowed)
				(pads allowed)
				(copperpour not_allowed)
				(footprints allowed)
			)
			(placement
				(enabled no)
				(sheetname "")
			)
			(fill
				(thermal_gap 0.5)
				(thermal_bridge_width 0.5)
				(island_removal_mode 0)
			)
			(polygon
				(pts
					(xy 498.416834 -23.911052) (xy 498.035834 -23.911052) (xy 498.035834 -23.403052) (xy 498.416834 -23.403052)
				)
			)
		)
		(zone
			(layer "F.Cu")
			(hatch none 0.5)
			(connect_pads
				(clearance 0)
			)
			(min_thickness 0.25)
			(keepout
				(tracks not_allowed)
				(vias allowed)
				(pads allowed)
				(copperpour not_allowed)
				(footprints allowed)
			)
			(placement
				(enabled no)
				(sheetname "")
			)
			(fill
				(thermal_gap 0.5)
				(thermal_bridge_width 0.5)
				(island_removal_mode 0)
			)
			(polygon
				(pts
					(xy 498.416834 -23.911052) (xy 498.035834 -23.911052) (xy 498.035834 -23.403052) (xy 498.416834 -23.403052)
				)
			)
		)
	)
)
